# T6G (Grand Teton) — schematic netlist excerpt (pin names and nets, part order shuffled) for the footprints in the layout excerpt that follows; sources: Cadence DE-HDL packaged netlist, KiCad conversion of 04192023_DAF0TMB3IC0_F0TG_MB_C_brd_V02_OCP.brd

R1239  Q_RES  1K 1% EMPTY  pkg 0402LF  page 258 : A = P3V3_AUX ; B = ADC128_2_A1
R778  Q_RES  84.5K 1% CHIP  pkg 0402LF  page 109 : A = PD_CHL_CPU1_DIMM_SAA ; B = GND
PJ09_P0_P  Q_SHORT  EMPTY  pkg SM  page 362 : \1\ = P0V9_CPU0_RT_2D ; \2\ = P0V9_RETIMER_CPU0_SENSE_SH_P

(kicad_pcb
	(version 20260206)
	(generator "pcbnew")
	(generator_version "10.0")
	(general
		(thickness 1.6)
		(legacy_teardrops no)
	)
	(paper "A4")
	(title_block
		(title "04192023_DAF0TMB3IC0_F0TG_MB_C_brd_V02_OCP.brd")
		(comment 1 "Grand Teton / footprints 7130-7133 of 8354")
	)
	(layers
		(0 "F.Cu" signal "TOP")
		(4 "In1.Cu" signal "GND")
		(6 "In2.Cu" signal "IN1")
		(8 "In3.Cu" signal "GND1")
		(10 "In4.Cu" signal "IN2")
		(12 "In5.Cu" signal "GND2")
		(14 "In6.Cu" signal "IN3")
		(16 "In7.Cu" signal "GND3")
		(18 "In8.Cu" signal "VCC")
		(20 "In9.Cu" signal "VCC1")
		(22 "In10.Cu" signal "GND4")
		(24 "In11.Cu" signal "IN4")
		(26 "In12.Cu" signal "GND5")
		(28 "In13.Cu" signal "IN5")
		(30 "In14.Cu" signal "GND6")
		(32 "In15.Cu" signal "IN6")
		(34 "In16.Cu" signal "GND7")
		(2 "B.Cu" signal "BOTTOM")
		(9 "F.Adhes" user "F.Adhesive")
		(11 "B.Adhes" user "B.Adhesive")
		(13 "F.Paste" user "Package Geometry/Pastemask Top")
		(15 "B.Paste" user "Package Geometry/Pastemask Bottom")
		(5 "F.SilkS" user "Ref Des/Silkscreen Top")
		(7 "B.SilkS" user "Ref Des/Silkscreen Bottom")
		(1 "F.Mask" user "Board Geometry/Soldermask Top")
		(3 "B.Mask" user "Board Geometry/Soldermask Bottom")
		(17 "Dwgs.User" user "User.Drawings")
		(19 "Cmts.User" user "User.Comments")
		(21 "Eco1.User" user "User.Eco1")
		(23 "Eco2.User" user "User.Eco2")
		(25 "Edge.Cuts" user "Board Geometry/Outline")
		(27 "Margin" user)
		(31 "F.CrtYd" user "Package Geometry/Place Bound Top")
		(29 "B.CrtYd" user "Package Geometry/Place Bound Bottom")
		(35 "F.Fab" user "Ref Des/Assembly Top")
		(33 "B.Fab" user "Ref Des/Assembly Bottom")
	)
	(footprint ""
		(layer "B.Cu")
		(at 202.903582 -194.885564 180)
		(property "Reference" "R778"
			(at 0 0 0)
			(layer "B.SilkS")
			(hide yes)
			(effects
				(font
					(size 1.27 1.27)
				)
				(justify mirror)
			)
		)
		(property "Value" ""
			(at 0 0 0)
			(layer "B.Fab")
			(effects
				(font
					(size 1.27 1.27)
				)
				(justify mirror)
			)
		)
		(duplicate_pad_numbers_are_jumpers no)
		(fp_line
			(start 0.7874 0.4064)
			(end 0.7874 -0.4064)
			(stroke
				(width 0.1524)
				(type default)
			)
			(layer "B.SilkS")
		)
		(fp_line
			(start 0.7874 -0.4064)
			(end -0.7874 -0.4064)
			(stroke
				(width 0.1524)
				(type default)
			)
			(layer "B.SilkS")
		)
		(fp_line
			(start -0.7874 0.4064)
			(end 0.7874 0.4064)
			(stroke
				(width 0.1524)
				(type default)
			)
			(layer "B.SilkS")
		)
		(fp_line
			(start -0.7874 -0.4064)
			(end -0.7874 0.4064)
			(stroke
				(width 0.1524)
				(type default)
			)
			(layer "B.SilkS")
		)
		(fp_line
			(start 0.67945 0.3048)
			(end 0.67945 -0.305054)
			(stroke
				(width 0.1)
				(type default)
			)
			(layer "B.Fab")
		)
		(fp_line
			(start 0.67945 -0.305054)
			(end 0.12065 -0.305054)
			(stroke
				(width 0.1)
				(type default)
			)
			(layer "B.Fab")
		)
		(fp_line
			(start 0.12065 0.3048)
			(end 0.67945 0.3048)
			(stroke
				(width 0.1)
				(type default)
			)
			(layer "B.Fab")
		)
		(fp_line
			(start 0.12065 0.2794)
			(end 0.12065 0.3048)
			(stroke
				(width 0.1)
				(type default)
			)
			(layer "B.Fab")
		)
		(fp_line
			(start 0.12065 -0.2794)
			(end -0.12065 -0.2794)
			(stroke
				(width 0.1)
				(type default)
			)
			(layer "B.Fab")
		)
		(fp_line
			(start 0.12065 -0.305054)
			(end 0.12065 -0.2794)
			(stroke
				(width 0.1)
				(type default)
			)
			(layer "B.Fab")
		)
		(fp_line
			(start -0.120396 0.3048)
			(end -0.120396 0.2794)
			(stroke
				(width 0.1)
				(type default)
			)
			(layer "B.Fab")
		)
		(fp_line
			(start -0.120396 0.2794)
			(end 0.12065 0.2794)
			(stroke
				(width 0.1)
				(type default)
			)
			(layer "B.Fab")
		)
		(fp_line
			(start -0.12065 -0.2794)
			(end -0.12065 -0.3048)
			(stroke
				(width 0.1)
				(type default)
			)
			(layer "B.Fab")
		)
		(fp_line
			(start -0.12065 -0.3048)
			(end -0.67945 -0.3048)
			(stroke
				(width 0.1)
				(type default)
			)
			(layer "B.Fab")
		)
		(fp_line
			(start -0.67945 0.3048)
			(end -0.120396 0.3048)
			(stroke
				(width 0.1)
				(type default)
			)
			(layer "B.Fab")
		)
		(fp_line
			(start -0.67945 -0.3048)
			(end -0.67945 0.3048)
			(stroke
				(width 0.1)
				(type default)
			)
			(layer "B.Fab")
		)
		(pad "1" smd circle
			(at 0.40005 0)
			(size 0 0)
			(layers "B.Cu" "B.Mask" "B.Paste")
			(net "PD_CHL_CPU1_DIMM_SAA")
		)
		(pad "2" smd circle
			(at -0.40005 0)
			(size 0 0)
			(layers "B.Cu" "B.Mask" "B.Paste")
			(net "GND")
		)
	)
	(footprint ""
		(layer "B.Cu")
		(at 216.13368 -329.179174 180)
		(property "Reference" "R1239"
			(at 0 0 0)
			(layer "B.SilkS")
			(hide yes)
			(effects
				(font
					(size 1.27 1.27)
				)
				(justify mirror)
			)
		)
		(property "Value" ""
			(at 0 0 0)
			(layer "B.Fab")
			(effects
				(font
					(size 1.27 1.27)
				)
				(justify mirror)
			)
		)
		(duplicate_pad_numbers_are_jumpers no)
		(fp_line
			(start 0.7874 0.4064)
			(end 0.7874 -0.4064)
			(stroke
				(width 0.1524)
				(type default)
			)
			(layer "B.SilkS")
		)
		(fp_line
			(start 0.7874 -0.4064)
			(end -0.7874 -0.4064)
			(stroke
				(width 0.1524)
				(type default)
			)
			(layer "B.SilkS")
		)
		(fp_line
			(start -0.7874 0.4064)
			(end 0.7874 0.4064)
			(stroke
				(width 0.1524)
				(type default)
			)
			(layer "B.SilkS")
		)
		(fp_line
			(start -0.7874 -0.4064)
			(end -0.7874 0.4064)
			(stroke
				(width 0.1524)
				(type default)
			)
			(layer "B.SilkS")
		)
		(fp_line
			(start 0.67945 0.3048)
			(end 0.67945 -0.305054)
			(stroke
				(width 0.1)
				(type default)
			)
			(layer "B.Fab")
		)
		(fp_line
			(start 0.67945 -0.305054)
			(end 0.12065 -0.305054)
			(stroke
				(width 0.1)
				(type default)
			)
			(layer "B.Fab")
		)
		(fp_line
			(start 0.12065 0.3048)
			(end 0.67945 0.3048)
			(stroke
				(width 0.1)
				(type default)
			)
			(layer "B.Fab")
		)
		(fp_line
			(start 0.12065 0.2794)
			(end 0.12065 0.3048)
			(stroke
				(width 0.1)
				(type default)
			)
			(layer "B.Fab")
		)
		(fp_line
			(start 0.12065 -0.2794)
			(end -0.12065 -0.2794)
			(stroke
				(width 0.1)
				(type default)
			)
			(layer "B.Fab")
		)
		(fp_line
			(start 0.12065 -0.305054)
			(end 0.12065 -0.2794)
			(stroke
				(width 0.1)
				(type default)
			)
			(layer "B.Fab")
		)
		(fp_line
			(start -0.120396 0.3048)
			(end -0.120396 0.2794)
			(stroke
				(width 0.1)
				(type default)
			)
			(layer "B.Fab")
		)
		(fp_line
			(start -0.120396 0.2794)
			(end 0.12065 0.2794)
			(stroke
				(width 0.1)
				(type default)
			)
			(layer "B.Fab")
		)
		(fp_line
			(start -0.12065 -0.2794)
			(end -0.12065 -0.3048)
			(stroke
				(width 0.1)
				(type default)
			)
			(layer "B.Fab")
		)
		(fp_line
			(start -0.12065 -0.3048)
			(end -0.67945 -0.3048)
			(stroke
				(width 0.1)
				(type default)
			)
			(layer "B.Fab")
		)
		(fp_line
			(start -0.67945 0.3048)
			(end -0.120396 0.3048)
			(stroke
				(width 0.1)
				(type default)
			)
			(layer "B.Fab")
		)
		(fp_line
			(start -0.67945 -0.3048)
			(end -0.67945 0.3048)
			(stroke
				(width 0.1)
				(type default)
			)
			(layer "B.Fab")
		)
		(pad "1" smd circle
			(at 0.40005 0)
			(size 0 0)
			(layers "B.Cu" "B.Mask" "B.Paste")
			(net "P3V3_AUX")
		)
		(pad "2" smd circle
			(at -0.40005 0)
			(size 0 0)
			(layers "B.Cu" "B.Mask" "B.Paste")
			(net "ADC128_2_A1")
		)
	)
	(footprint ""
		(layer "B.Cu")
		(at 367.186464 -63.155068)
		(property "Reference" "ME13"
			(at 0 0 0)
			(layer "B.SilkS")
			(hide yes)
			(effects
				(font
					(size 1.27 1.27)
				)
				(justify mirror)
			)
		)
		(property "Value" ""
			(at 0 0 0)
			(layer "B.Fab")
			(effects
				(font
					(size 1.27 1.27)
				)
				(justify mirror)
			)
		)
		(duplicate_pad_numbers_are_jumpers no)
		(zone
			(layer "B.Cu")
			(hatch none 0.5)
			(connect_pads
				(clearance 0)
			)
			(min_thickness 0.25)
			(keepout
				(tracks allowed)
				(vias allowed)
				(pads allowed)
				(copperpour allowed)
				(footprints not_allowed)
			)
			(placement
				(enabled no)
				(sheetname "")
			)
			(fill
				(thermal_gap 0.5)
				(thermal_bridge_width 0.5)
				(island_removal_mode 0)
			)
			(polygon
				(pts
					(arc
						(start 377.186444 -63.155068)
						(mid 357.186484 -63.155068)
						(end 377.186444 -63.155068)
					)
				)
			)
		)
	)
	(footprint ""
		(layer "B.Cu")
		(at 304.055018 -409.560014 90)
		(property "Reference" "PJ09_P0_P"
			(at 0 0 90)
			(layer "B.SilkS")
			(hide yes)
			(effects
				(font
					(size 1.27 1.27)
				)
				(justify mirror)
			)
		)
		(property "Value" ""
			(at 0 0 90)
			(layer "B.Fab")
			(effects
				(font
					(size 1.27 1.27)
				)
				(justify mirror)
			)
		)
		(duplicate_pad_numbers_are_jumpers no)
		(zone
			(layer "In11.Cu")
			(hatch none 0.5)
			(connect_pads
				(clearance 0)
			)
			(min_thickness 0.25)
			(keepout
				(tracks allowed)
				(vias not_allowed)
				(pads allowed)
				(copperpour not_allowed)
				(footprints allowed)
			)
			(placement
				(enabled no)
				(sheetname "")
			)
			(fill
				(thermal_gap 0.5)
				(thermal_bridge_width 0.5)
				(island_removal_mode 0)
			)
			(polygon
				(pts
					(xy 304.245518 -409.775914) (xy 304.245518 -409.344114) (xy 303.864518 -409.344114) (xy 303.864518 -409.775914)
				)
			)
		)
	)
)
